(kicad_sch (version 20230121) (generator eeschema)

  (paper "A3")

  (title_block
    (title "Kria K26 Devboard")
    (date "2024-03-26")
    (rev "1.2.5")
    (comment 1 "www.antmicro.com")
    (comment 2 "Antmicro Ltd.")
  )

  (junction (at 153.035 90.805) (diameter 0) (color 0 0 0 0)
  )
  (junction (at 194.945 90.805) (diameter 0) (color 0 0 0 0)
  )
  (junction (at 73.025 93.98) (diameter 0) (color 0 0 0 0)
  )
  (junction (at 217.805 90.805) (diameter 0) (color 0 0 0 0)
  )
  (junction (at 150.495 90.805) (diameter 0) (color 0 0 0 0)
  )
  (junction (at 162.56 67.945) (diameter 0) (color 0 0 0 0)
  )
  (junction (at 162.56 45.085) (diameter 0) (color 0 0 0 0)
  )
  (junction (at 145.415 106.045) (diameter 0) (color 0 0 0 0)
  )
  (junction (at 150.495 106.045) (diameter 0) (color 0 0 0 0)
  )
  (junction (at 147.32 45.085) (diameter 0) (color 0 0 0 0)
  )
  (junction (at 217.805 106.045) (diameter 0) (color 0 0 0 0)
  )
  (junction (at 194.945 106.045) (diameter 0) (color 0 0 0 0)
  )
  (junction (at 128.27 45.085) (diameter 0) (color 0 0 0 0)
  )
  (junction (at 107.315 60.325) (diameter 0) (color 0 0 0 0)
  )
  (junction (at 86.995 93.98) (diameter 0) (color 0 0 0 0)
  )
  (junction (at 186.055 67.945) (diameter 0) (color 0 0 0 0)
  )
  (junction (at 80.01 93.98) (diameter 0) (color 0 0 0 0)
  )
  (junction (at 139.065 45.085) (diameter 0) (color 0 0 0 0)
  )
  (junction (at 196.85 90.805) (diameter 0) (color 0 0 0 0)
  )
  (junction (at 206.375 90.805) (diameter 0) (color 0 0 0 0)
  )
  (junction (at 153.67 45.085) (diameter 0) (color 0 0 0 0)
  )
  (junction (at 145.415 90.805) (diameter 0) (color 0 0 0 0)
  )
  (junction (at 153.67 69.85) (diameter 0) (color 0 0 0 0)
  )
  (junction (at 139.065 69.85) (diameter 0) (color 0 0 0 0)
  )
  (junction (at 59.055 93.98) (diameter 0) (color 0 0 0 0)
  )
  (junction (at 93.98 93.98) (diameter 0) (color 0 0 0 0)
  )
  (junction (at 206.375 106.045) (diameter 0) (color 0 0 0 0)
  )
  (junction (at 66.04 93.98) (diameter 0) (color 0 0 0 0)
  )
  (junction (at 100.965 93.98) (diameter 0) (color 0 0 0 0)
  )
  (junction (at 147.32 69.85) (diameter 0) (color 0 0 0 0)
  )

  (no_connect (at 184.15 56.515))
  (no_connect (at 188.595 98.425))

  (bus_entry (at 97.155 55.245) (size -2.54 -2.54)
    (stroke (width 0) (type default))
  )
  (bus_entry (at 97.155 40.005) (size -2.54 -2.54)
    (stroke (width 0) (type default))
  )
  (bus_entry (at 97.155 50.165) (size -2.54 -2.54)
    (stroke (width 0) (type default))
  )
  (bus_entry (at 97.155 65.405) (size -2.54 -2.54)
    (stroke (width 0) (type default))
  )

  (wire (pts (xy 150.495 90.805) (xy 153.035 90.805))
    (stroke (width 0) (type default))
  )
  (wire (pts (xy 139.065 45.085) (xy 147.32 45.085))
    (stroke (width 0) (type default))
  )
  (wire (pts (xy 145.415 97.155) (xy 145.415 97.79))
    (stroke (width 0) (type default))
  )
  (wire (pts (xy 162.56 45.085) (xy 162.56 53.975))
    (stroke (width 0) (type default))
  )
  (wire (pts (xy 153.67 53.34) (xy 153.67 56.515))
    (stroke (width 0) (type default))
  )
  (wire (pts (xy 217.805 107.315) (xy 217.805 106.045))
    (stroke (width 0) (type default))
  )
  (bus (pts (xy 94.615 37.465) (xy 94.615 47.625))
    (stroke (width 0) (type default))
  )

  (wire (pts (xy 59.055 97.79) (xy 59.055 93.98))
    (stroke (width 0) (type default))
  )
  (wire (pts (xy 100.965 97.79) (xy 100.965 93.98))
    (stroke (width 0) (type default))
  )
  (polyline (pts (xy 114.935 103.505) (xy 114.935 96.52))
    (stroke (width 0) (type default))
  )

  (wire (pts (xy 86.995 93.98) (xy 93.98 93.98))
    (stroke (width 0) (type default))
  )
  (wire (pts (xy 128.27 45.085) (xy 126.365 45.085))
    (stroke (width 0) (type default))
  )
  (wire (pts (xy 206.375 106.045) (xy 217.805 106.045))
    (stroke (width 0) (type default))
  )
  (wire (pts (xy 145.415 90.805) (xy 150.495 90.805))
    (stroke (width 0) (type default))
  )
  (wire (pts (xy 59.055 93.98) (xy 66.04 93.98))
    (stroke (width 0) (type default))
  )
  (wire (pts (xy 196.85 90.805) (xy 206.375 90.805))
    (stroke (width 0) (type default))
  )
  (wire (pts (xy 139.065 69.85) (xy 147.32 69.85))
    (stroke (width 0) (type default))
  )
  (wire (pts (xy 145.415 90.805) (xy 145.415 92.075))
    (stroke (width 0) (type default))
  )
  (wire (pts (xy 108.585 65.405) (xy 97.155 65.405))
    (stroke (width 0) (type default))
  )
  (wire (pts (xy 107.315 60.325) (xy 108.585 60.325))
    (stroke (width 0) (type default))
  )
  (bus (pts (xy 93.345 36.195) (xy 94.615 36.195))
    (stroke (width 0) (type default))
  )

  (wire (pts (xy 108.585 45.085) (xy 107.315 45.085))
    (stroke (width 0) (type default))
  )
  (wire (pts (xy 147.32 69.85) (xy 153.67 69.85))
    (stroke (width 0) (type default))
  )
  (wire (pts (xy 147.32 45.085) (xy 153.67 45.085))
    (stroke (width 0) (type default))
  )
  (wire (pts (xy 145.415 106.045) (xy 150.495 106.045))
    (stroke (width 0) (type default))
  )
  (bus (pts (xy 94.615 52.705) (xy 94.615 62.865))
    (stroke (width 0) (type default))
  )

  (wire (pts (xy 93.98 93.98) (xy 100.965 93.98))
    (stroke (width 0) (type default))
  )
  (wire (pts (xy 153.67 45.085) (xy 153.67 48.26))
    (stroke (width 0) (type default))
  )
  (wire (pts (xy 194.945 106.045) (xy 206.375 106.045))
    (stroke (width 0) (type default))
  )
  (wire (pts (xy 153.67 45.085) (xy 162.56 45.085))
    (stroke (width 0) (type default))
  )
  (wire (pts (xy 66.04 97.79) (xy 66.04 93.98))
    (stroke (width 0) (type default))
  )
  (wire (pts (xy 194.945 95.885) (xy 194.945 90.805))
    (stroke (width 0) (type default))
  )
  (wire (pts (xy 184.15 53.975) (xy 186.055 53.975))
    (stroke (width 0) (type default))
  )
  (polyline (pts (xy 56.515 96.52) (xy 56.515 103.505))
    (stroke (width 0) (type default))
  )

  (wire (pts (xy 100.965 93.98) (xy 107.95 93.98))
    (stroke (width 0) (type default))
  )
  (wire (pts (xy 162.56 67.945) (xy 162.56 69.85))
    (stroke (width 0) (type default))
  )
  (wire (pts (xy 163.83 62.865) (xy 153.67 62.865))
    (stroke (width 0) (type default))
  )
  (wire (pts (xy 80.01 97.79) (xy 80.01 93.98))
    (stroke (width 0) (type default))
  )
  (wire (pts (xy 153.67 62.865) (xy 153.67 63.5))
    (stroke (width 0) (type default))
  )
  (wire (pts (xy 93.98 97.79) (xy 93.98 93.98))
    (stroke (width 0) (type default))
  )
  (wire (pts (xy 150.495 90.805) (xy 150.495 92.075))
    (stroke (width 0) (type default))
  )
  (wire (pts (xy 128.27 45.085) (xy 139.065 45.085))
    (stroke (width 0) (type default))
  )
  (wire (pts (xy 206.375 95.885) (xy 206.375 90.805))
    (stroke (width 0) (type default))
  )
  (wire (pts (xy 86.995 97.79) (xy 86.995 93.98))
    (stroke (width 0) (type default))
  )
  (wire (pts (xy 153.035 90.805) (xy 153.035 89.535))
    (stroke (width 0) (type default))
  )
  (wire (pts (xy 126.365 60.325) (xy 128.27 60.325))
    (stroke (width 0) (type default))
  )
  (wire (pts (xy 107.95 97.79) (xy 107.95 93.98))
    (stroke (width 0) (type default))
  )
  (bus (pts (xy 94.615 36.195) (xy 94.615 37.465))
    (stroke (width 0) (type default))
  )

  (wire (pts (xy 128.27 60.325) (xy 128.27 45.085))
    (stroke (width 0) (type default))
  )
  (wire (pts (xy 147.32 45.085) (xy 147.32 57.15))
    (stroke (width 0) (type default))
  )
  (wire (pts (xy 157.099 98.425) (xy 168.275 98.425))
    (stroke (width 0) (type default))
  )
  (wire (pts (xy 226.06 90.805) (xy 217.805 90.805))
    (stroke (width 0) (type default))
  )
  (wire (pts (xy 162.56 65.405) (xy 162.56 67.945))
    (stroke (width 0) (type default))
  )
  (wire (pts (xy 108.585 40.005) (xy 97.155 40.005))
    (stroke (width 0) (type default))
  )
  (wire (pts (xy 206.375 100.965) (xy 206.375 106.045))
    (stroke (width 0) (type default))
  )
  (wire (pts (xy 150.495 106.045) (xy 168.275 106.045))
    (stroke (width 0) (type default))
  )
  (wire (pts (xy 73.025 97.79) (xy 73.025 93.98))
    (stroke (width 0) (type default))
  )
  (wire (pts (xy 153.67 56.515) (xy 163.83 56.515))
    (stroke (width 0) (type default))
  )
  (wire (pts (xy 139.065 45.085) (xy 139.065 54.61))
    (stroke (width 0) (type default))
  )
  (wire (pts (xy 150.495 97.155) (xy 150.495 106.045))
    (stroke (width 0) (type default))
  )
  (wire (pts (xy 162.56 53.975) (xy 163.83 53.975))
    (stroke (width 0) (type default))
  )
  (wire (pts (xy 145.415 106.045) (xy 145.415 107.95))
    (stroke (width 0) (type default))
  )
  (wire (pts (xy 217.805 106.045) (xy 217.805 100.965))
    (stroke (width 0) (type default))
  )
  (wire (pts (xy 162.56 67.945) (xy 163.83 67.945))
    (stroke (width 0) (type default))
  )
  (wire (pts (xy 162.56 45.085) (xy 197.485 45.085))
    (stroke (width 0) (type default))
  )
  (wire (pts (xy 66.04 93.98) (xy 73.025 93.98))
    (stroke (width 0) (type default))
  )
  (wire (pts (xy 147.32 69.85) (xy 147.32 62.23))
    (stroke (width 0) (type default))
  )
  (wire (pts (xy 196.85 90.805) (xy 194.945 90.805))
    (stroke (width 0) (type default))
  )
  (wire (pts (xy 108.585 55.245) (xy 97.155 55.245))
    (stroke (width 0) (type default))
  )
  (wire (pts (xy 184.15 67.945) (xy 186.055 67.945))
    (stroke (width 0) (type default))
  )
  (wire (pts (xy 153.67 69.85) (xy 162.56 69.85))
    (stroke (width 0) (type default))
  )
  (wire (pts (xy 206.375 90.805) (xy 217.805 90.805))
    (stroke (width 0) (type default))
  )
  (wire (pts (xy 108.585 50.165) (xy 97.155 50.165))
    (stroke (width 0) (type default))
  )
  (wire (pts (xy 139.065 69.85) (xy 139.065 63.5))
    (stroke (width 0) (type default))
  )
  (wire (pts (xy 73.025 93.98) (xy 80.01 93.98))
    (stroke (width 0) (type default))
  )
  (wire (pts (xy 217.805 90.805) (xy 217.805 95.885))
    (stroke (width 0) (type default))
  )
  (bus (pts (xy 94.615 47.625) (xy 94.615 52.705))
    (stroke (width 0) (type default))
  )

  (polyline (pts (xy 56.515 96.52) (xy 114.935 96.52))
    (stroke (width 0) (type default))
  )

  (wire (pts (xy 184.15 59.055) (xy 197.485 59.055))
    (stroke (width 0) (type default))
  )
  (polyline (pts (xy 56.515 103.505) (xy 114.935 103.505))
    (stroke (width 0) (type default))
  )

  (wire (pts (xy 107.315 69.85) (xy 107.315 60.325))
    (stroke (width 0) (type default))
  )
  (wire (pts (xy 107.315 69.85) (xy 139.065 69.85))
    (stroke (width 0) (type default))
  )
  (wire (pts (xy 188.595 106.045) (xy 194.945 106.045))
    (stroke (width 0) (type default))
  )
  (wire (pts (xy 153.035 90.805) (xy 168.275 90.805))
    (stroke (width 0) (type default))
  )
  (wire (pts (xy 194.945 100.965) (xy 194.945 106.045))
    (stroke (width 0) (type default))
  )
  (wire (pts (xy 196.85 90.805) (xy 196.85 89.535))
    (stroke (width 0) (type default))
  )
  (wire (pts (xy 80.01 93.98) (xy 86.995 93.98))
    (stroke (width 0) (type default))
  )
  (wire (pts (xy 153.67 68.58) (xy 153.67 69.85))
    (stroke (width 0) (type default))
  )
  (wire (pts (xy 186.055 67.945) (xy 186.055 69.215))
    (stroke (width 0) (type default))
  )
  (wire (pts (xy 132.715 90.805) (xy 145.415 90.805))
    (stroke (width 0) (type default))
  )
  (wire (pts (xy 47.625 93.98) (xy 59.055 93.98))
    (stroke (width 0) (type default))
  )
  (wire (pts (xy 107.315 45.085) (xy 107.315 60.325))
    (stroke (width 0) (type default))
  )
  (wire (pts (xy 145.415 105.41) (xy 145.415 106.045))
    (stroke (width 0) (type default))
  )
  (wire (pts (xy 188.595 90.805) (xy 194.945 90.805))
    (stroke (width 0) (type default))
  )
  (wire (pts (xy 163.83 65.405) (xy 162.56 65.405))
    (stroke (width 0) (type default))
  )
  (wire (pts (xy 186.055 53.975) (xy 186.055 67.945))
    (stroke (width 0) (type default))
  )

  (text "PoE PD\n" (at 13.97 17.78 0)
    (effects (font (size 2.54 2.54) (thickness 0.508) bold) (justify left bottom))
  )
  (text "Maintain POE\nwith low load" (at 151.13 110.49 0)
    (effects (font (size 1.27 1.27)) (justify left bottom))
  )
  (text "8x 22u/100V" (at 78.105 93.345 0)
    (effects (font (size 1.27 1.27)) (justify left bottom))
  )

  (label "POE_VC1" (at 97.155 40.005 0) (fields_autoplaced)
    (effects (font (size 1.27 1.27)) (justify left bottom))
  )
  (label "POE_ACTIVE" (at 157.099 98.425 0) (fields_autoplaced)
    (effects (font (size 1.27 1.27)) (justify left bottom))
  )
  (label "POE_VC4" (at 97.155 65.405 0) (fields_autoplaced)
    (effects (font (size 1.27 1.27)) (justify left bottom))
  )
  (label "POE_VC2" (at 97.155 50.165 0) (fields_autoplaced)
    (effects (font (size 1.27 1.27)) (justify left bottom))
  )
  (label "POE_VC3" (at 97.155 55.245 0) (fields_autoplaced)
    (effects (font (size 1.27 1.27)) (justify left bottom))
  )
  (label "POE_ACTIVE" (at 197.485 59.055 180) (fields_autoplaced)
    (effects (font (size 1.27 1.27)) (justify right bottom))
  )
  (label "VDD_POE_IN" (at 132.715 90.805 0) (fields_autoplaced)
    (effects (font (size 1.27 1.27)) (justify left bottom))
  )
  (label "VDD_POE_IN" (at 47.625 93.98 0) (fields_autoplaced)
    (effects (font (size 1.27 1.27)) (justify left bottom))
  )
  (label "VSS_POE_IN" (at 124.46 69.85 0) (fields_autoplaced)
    (effects (font (size 1.27 1.27)) (justify left bottom))
  )
  (label "VDD_POE_IN" (at 197.485 45.085 180) (fields_autoplaced)
    (effects (font (size 1.27 1.27)) (justify right bottom))
  )

  (hierarchical_label "POE_VC[1..4]" (shape input) (at 93.345 36.195 180) (fields_autoplaced)
    (effects (font (size 1.27 1.27)) (justify right))
  )
  (hierarchical_label "POE_12V" (shape input) (at 226.06 90.805 0) (fields_autoplaced)
    (effects (font (size 1.27 1.27)) (justify left))
  )

  (symbol (lib_id "kria-k26-devboard:MB10S") (at 108.585 40.005 0) (unit 1)
    (in_bom yes) (on_board yes) (dnp no)
    (property "Reference" "D8" (at 127.635 39.37 0)
      (effects (font (size 1.27 1.27)))
    )
    (property "Value" "MB10S" (at 117.475 32.6253 0)
      (effects (font (size 1.27 1.27) (thickness 0.15)) (justify left bottom) hide)
    )
    (property "Footprint" "kria-k26-devboard-footprints:SOIC-4_W3.9mm" (at 94.615 41.275 0)
      (effects (font (size 1.27 1.27) (thickness 0.15)) (justify left bottom) hide)
    )
    (property "Datasheet" "http://www.farnell.com/datasheets/2895435.pdf" (at 94.615 41.275 0)
      (effects (font (size 1.27 1.27) (thickness 0.15)) (justify left bottom) hide)
    )
    (property "MPN" "MB10S" (at 127.635 41.91 0)
      (effects (font (size 1.27 1.27) (thickness 0.15)))
    )
    (property "Manufacturer" "Multicomp Pro" (at 117.475 37.6991 0)
      (effects (font (size 1.27 1.27) (thickness 0.15)) (justify left bottom) hide)
    )
    (property "Author" "Antmicro" (at 123.825 55.245 0)
      (effects (font (size 1.27 1.27) (thickness 0.15)) (justify left bottom) hide)
    )
    (property "License" "Apache-2.0" (at 123.825 57.785 0)
      (effects (font (size 1.27 1.27) (thickness 0.15)) (justify left bottom) hide)
    )
    (pin "1")
    (pin "2")
    (pin "3")
    (pin "4")
    (instances
      (project "kria-k26-devboard"
        (path ""
          (reference "D8") (unit 1)
        )
      )
    )
  )

  (symbol (lib_id "kria-k26-devboard:MB10S") (at 108.585 55.245 0) (unit 1)
    (in_bom yes) (on_board yes) (dnp no)
    (property "Reference" "D9" (at 127.635 62.23 0)
      (effects (font (size 1.27 1.27)))
    )
    (property "Value" "MB10S" (at 117.475 71.1153 0)
      (effects (font (size 1.27 1.27) (thickness 0.15)) (justify left bottom) hide)
    )
    (property "Footprint" "kria-k26-devboard-footprints:SOIC-4_W3.9mm" (at 94.615 56.515 0)
      (effects (font (size 1.27 1.27) (thickness 0.15)) (justify left bottom) hide)
    )
    (property "Datasheet" "http://www.farnell.com/datasheets/2895435.pdf" (at 94.615 56.515 0)
      (effects (font (size 1.27 1.27) (thickness 0.15)) (justify left bottom) hide)
    )
    (property "MPN" "MB10S" (at 127.635 64.77 0)
      (effects (font (size 1.27 1.27) (thickness 0.15)))
    )
    (property "Manufacturer" "Multicomp Pro" (at 117.475 76.1891 0)
      (effects (font (size 1.27 1.27) (thickness 0.15)) (justify left bottom) hide)
    )
    (property "Author" "Antmicro" (at 123.825 70.485 0)
      (effects (font (size 1.27 1.27) (thickness 0.15)) (justify left bottom) hide)
    )
    (property "License" "Apache-2.0" (at 123.825 73.025 0)
      (effects (font (size 1.27 1.27) (thickness 0.15)) (justify left bottom) hide)
    )
    (pin "1")
    (pin "2")
    (pin "3")
    (pin "4")
    (instances
      (project "kria-k26-devboard"
        (path ""
          (reference "D9") (unit 1)
        )
      )
    )
  )

  (symbol (lib_id "kria-k26-devboard:SMAJ58A-13-F") (at 139.065 63.5 90) (unit 1)
    (in_bom yes) (on_board yes) (dnp no)
    (property "Reference" "D10" (at 140.97 66.04 0)
      (effects (font (size 1.524 1.524)) (justify left))
    )
    (property "Value" "SMAJ58A-13-F" (at 142.875 54.61 0)
      (effects (font (size 1.27 1.27) (thickness 0.15)) (justify left bottom) hide)
    )
    (property "Footprint" "kria-k26-devboard-footprints:DO-214AC" (at 133.985 58.42 0)
      (effects (font (size 1.27 1.27) (thickness 0.15)) (justify left bottom) hide)
    )
    (property "Datasheet" "https://4donline.ihs.com/images/VipMasterIC/IC/DIOD/DIOD-S-A0001754755/DIOD-S-A0001754755-1.pdf?hkey=52A5661711E402568146F3353EA87419" (at 131.445 58.42 0)
      (effects (font (size 1.27 1.27) (thickness 0.15)) (justify left bottom) hide)
    )
    (property "MPN" "SMAJ58A-13-F" (at 143.51 66.04 0)
      (effects (font (size 1.27 1.27) (thickness 0.15)) (justify left))
    )
    (property "Manufacturer" "Diodes Incorporated" (at 111.125 58.42 0)
      (effects (font (size 1.27 1.27) (thickness 0.15)) (justify left bottom) hide)
    )
    (property "Author" "Antmicro" (at 159.385 41.91 0)
      (effects (font (size 1.27 1.27) (thickness 0.15)) (justify left bottom) hide)
    )
    (property "License" "Apache-2.0" (at 161.925 41.91 0)
      (effects (font (size 1.27 1.27) (thickness 0.15)) (justify left bottom) hide)
    )
    (pin "A")
    (pin "K")
    (instances
      (project "kria-k26-devboard"
        (path ""
          (reference "D10") (unit 1)
        )
      )
    )
  )

  (symbol (lib_id "kria-k26-devboard:R_24k9_0402") (at 153.67 48.26 270) (unit 1)
    (in_bom yes) (on_board yes) (dnp no) (fields_autoplaced)
    (property "Reference" "R115" (at 155.575 49.53 90)
      (effects (font (size 1.524 1.524)) (justify left))
    )
    (property "Value" "R_24k9_0402" (at 149.86 48.26 0)
      (effects (font (size 1.27 1.27) (thickness 0.15)) (justify left bottom) hide)
    )
    (property "Footprint" "kria-k26-devboard-footprints:R_0402_1005Metric" (at 158.75 53.34 0)
      (effects (font (size 1.27 1.27) (thickness 0.15)) (justify left bottom) hide)
    )
    (property "Datasheet" "https://www.bourns.com/docs/product-datasheets/cr.pdf" (at 153.67 48.26 0)
      (effects (font (size 1.27 1.27) (thickness 0.15)) (justify left bottom) hide)
    )
    (property "Manufacturer" "Bourns" (at 163.83 53.34 0)
      (effects (font (size 1.27 1.27) (thickness 0.15)) (justify left bottom) hide)
    )
    (property "MPN" "CR0402-FX-2492GLF" (at 161.29 53.34 0)
      (effects (font (size 1.27 1.27) (thickness 0.15)) (justify left bottom) hide)
    )
    (property "Val" "24k9" (at 155.575 52.7049 90)
      (effects (font (size 1.27 1.27) (thickness 0.15)) (justify left))
    )
    (property "License" "Apache-2.0" (at 128.27 68.58 0)
      (effects (font (size 1.27 1.27) (thickness 0.15)) (justify left bottom) hide)
    )
    (property "Author" "Antmicro" (at 125.73 68.58 0)
      (effects (font (size 1.27 1.27) (thickness 0.15)) (justify left bottom) hide)
    )
    (property "Tolerance" "1%" (at 143.51 68.58 0)
      (effects (font (size 1.27 1.27)) (justify left bottom) hide)
    )
    (pin "1")
    (pin "2")
    (instances
      (project "kria-k26-devboard"
        (path ""
          (reference "R115") (unit 1)
        )
      )
    )
  )

  (symbol (lib_id "kria-k26-devboard:GNDD") (at 186.055 69.215 0) (unit 1)
    (in_bom yes) (on_board yes) (dnp no)
    (property "Reference" "#PWR0363" (at 186.055 75.565 0)
      (effects (font (size 1.27 1.27)) hide)
    )
    (property "Value" "GNDD" (at 186.1566 73.152 0)
      (effects (font (size 1.27 1.27)))
    )
    (property "Footprint" "" (at 201.295 79.375 0)
      (effects (font (size 1.27 1.27) (thickness 0.15)) (justify left bottom) hide)
    )
    (property "Datasheet" "" (at 201.295 81.915 0)
      (effects (font (size 1.27 1.27) (thickness 0.15)) (justify left bottom) hide)
    )
    (property "Author" "Antmicro" (at 201.295 76.835 0)
      (effects (font (size 1.27 1.27) (thickness 0.15)) (justify left bottom) hide)
    )
    (property "License" "Apache-2.0" (at 201.295 79.375 0)
      (effects (font (size 1.27 1.27) (thickness 0.15)) (justify left bottom) hide)
    )
    (pin "1")
    (instances
      (project "kria-k26-devboard"
        (path ""
          (reference "#PWR0363") (unit 1)
        )
      )
    )
  )

  (symbol (lib_id "kria-k26-devboard:PDQE30-Q48-S12-D") (at 168.275 90.805 0) (unit 1)
    (in_bom yes) (on_board yes) (dnp no) (fields_autoplaced)
    (property "Reference" "PS1" (at 178.435 83.185 0)
      (effects (font (size 1.27 1.27)))
    )
    (property "Value" "PDQE30-Q48-S12-D" (at 168.275 81.2546 0)
      (effects (font (size 1.27 1.27) (thickness 0.15)) (justify left bottom) hide)
    )
    (property "Footprint" "kria-k26-devboard-footprints:CONV_PDQE30-Q48-S5-D" (at 168.275 90.805 0)
      (effects (font (size 1.27 1.27) (thickness 0.15)) (justify left bottom) hide)
    )
    (property "Datasheet" "https://www.cui.com/product/resource/pdqe30-d.pdf" (at 168.275 90.805 0)
      (effects (font (size 1.27 1.27) (thickness 0.15)) (justify left bottom) hide)
    )
    (property "MPN" "PDQE30-Q48-S12-D" (at 178.435 85.725 0)
      (effects (font (size 1.27 1.27) (thickness 0.15)))
    )
    (property "Manufacturer" "CUI Inc" (at 168.275 90.805 0)
      (effects (font (size 1.27 1.27) (thickness 0.15)) (justify left bottom) hide)
    )
    (property "Author" "Antmicro" (at 203.835 111.125 0)
      (effects (font (size 1.27 1.27) (thickness 0.15)) (justify left bottom) hide)
    )
    (property "License" "Apache-2.0" (at 203.835 113.665 0)
      (effects (font (size 1.27 1.27) (thickness 0.15)) (justify left bottom) hide)
    )
    (pin "1")
    (pin "2")
    (pin "3")
    (pin "4")
    (pin "5")
    (pin "6")
    (instances
      (project "kria-k26-devboard"
        (path ""
          (reference "PS1") (unit 1)
        )
      )
    )
  )

  (symbol (lib_id "kria-k26-devboard:TPS2378DDA") (at 163.83 53.975 0) (unit 1)
    (in_bom yes) (on_board yes) (dnp no)
    (property "Reference" "IC1" (at 173.99 46.99 0)
      (effects (font (size 1.27 1.27)))
    )
    (property "Value" "TPS2378DDA" (at 173.99 49.53 0)
      (effects (font (size 1.27 1.27) (thickness 0.15)))
    )
    (property "Footprint" "kria-k26-devboard-footprints:SOIC-8-1EP_3.9x4.9x1.75mm_P1.27mm" (at 199.39 59.055 0)
      (effects (font (size 1.27 1.27) (thickness 0.15)) (justify left bottom) hide)
    )
    (property "Datasheet" "http://www.ti.com/lit/ds/symlink/tps2378.pdf" (at 199.39 61.595 0)
      (effects (font (size 1.27 1.27) (thickness 0.15)) (justify left bottom) hide)
    )
    (property "Manufacturer" "Texas Instruments" (at 199.39 64.135 0)
      (effects (font (size 1.27 1.27) (thickness 0.15)) (justify left bottom) hide)
    )
    (property "MPN" "TPS2378DDA" (at 199.39 66.675 0)
      (effects (font (size 1.27 1.27) (thickness 0.15)) (justify left bottom) hide)
    )
    (property "Author" "Antmicro" (at 199.39 69.215 0)
      (effects (font (size 1.27 1.27) (thickness 0.15)) (justify left bottom) hide)
    )
    (property "License" "Apache-2.0" (at 199.39 71.755 0)
      (effects (font (size 1.27 1.27) (thickness 0.15)) (justify left bottom) hide)
    )
    (pin "1")
    (pin "2")
    (pin "3")
    (pin "4")
    (pin "5")
    (pin "6")
    (pin "7")
    (pin "8")
    (pin "9")
    (instances
      (project "kria-k26-devboard"
        (path ""
          (reference "IC1") (unit 1)
        )
      )
    )
  )

  (symbol (lib_id "kria-k26-devboard:C_100n_100V_0805") (at 147.32 57.15 270) (unit 1)
    (in_bom yes) (on_board yes) (dnp no)
    (property "Reference" "C171" (at 149.86 58.4263 90)
      (effects (font (size 1.524 1.524)) (justify left))
    )
    (property "Value" "C_100n_0805_100V" (at 143.51 57.15 0)
      (effects (font (size 1.27 1.27) (thickness 0.15)) (justify left bottom) hide)
    )
    (property "Footprint" "kria-k26-devboard-footprints:C_0805_2012Metric" (at 152.4 62.23 0)
      (effects (font (size 1.27 1.27) (thickness 0.15)) (justify left bottom) hide)
    )
    (property "Datasheet" "https://www.mouser.pl/datasheet/2/585/MLCC-1837944.pdf" (at 147.32 57.15 0)
      (effects (font (size 1.27 1.27) (thickness 0.15)) (justify left bottom) hide)
    )
    (property "Manufacturer" "SAMSUNG" (at 157.48 62.23 0)
      (effects (font (size 1.27 1.27) (thickness 0.15)) (justify left bottom) hide)
    )
    (property "MPN" "CL21B104KCFNNNE" (at 154.94 62.23 0)
      (effects (font (size 1.27 1.27) (thickness 0.15)) (justify left bottom) hide)
    )
    (property "Val" "100n/100V" (at 149.86 60.96 90)
      (effects (font (size 1.27 1.27) (thickness 0.15)) (justify left))
    )
    (property "License" "Apache-2.0" (at 124.46 77.47 0)
      (effects (font (size 1.27 1.27) (thickness 0.15)) (justify left bottom) hide)
    )
    (property "Author" "Antmicro" (at 121.92 77.47 0)
      (effects (font (size 1.27 1.27) (thickness 0.15)) (justify left bottom) hide)
    )
    (property "Voltage" "100V" (at 119.38 77.47 0)
      (effects (font (size 1.27 1.27)) (justify left bottom) hide)
    )
    (property "Dielectric" "X7R" (at 116.84 77.47 0)
      (effects (font (size 1.27 1.27)) (justify left bottom) hide)
    )
    (pin "1")
    (pin "2")
    (instances
      (project "kria-k26-devboard"
        (path ""
          (reference "C171") (unit 1)
        )
      )
    )
  )

  (symbol (lib_id "kria-k26-devboard:C_47u_16V_1206") (at 194.945 95.885 270) (unit 1)
    (in_bom yes) (on_board yes) (dnp no)
    (property "Reference" "C180" (at 195.58 96.52 90)
      (effects (font (size 1.524 1.524)) (justify left))
    )
    (property "Value" "C_47u_16V_1206" (at 191.135 95.885 0)
      (effects (font (size 1.27 1.27) (thickness 0.15)) (justify left bottom) hide)
    )
    (property "Footprint" "kria-k26-devboard-footprints:C_1206_3216Metric" (at 200.025 100.965 0)
      (effects (font (size 1.27 1.27) (thickness 0.15)) (justify left bottom) hide)
    )
    (property "Datasheet" " " (at 194.945 95.885 0)
      (effects (font (size 1.27 1.27) (thickness 0.15)) (justify left bottom) hide)
    )
    (property "Manufacturer" "TDK" (at 205.105 100.965 0)
      (effects (font (size 1.27 1.27) (thickness 0.15)) (justify left bottom) hide)
    )
    (property "MPN" "C3216X5R1C476M160AB" (at 202.565 100.965 0)
      (effects (font (size 1.27 1.27) (thickness 0.15)) (justify left bottom) hide)
    )
    (property "Val" "47u/16V" (at 195.58 100.33 90)
      (effects (font (size 1.27 1.27) (thickness 0.15)) (justify left))
    )
    (property "License" "Apache-2.0" (at 172.085 116.205 0)
      (effects (font (size 1.27 1.27) (thickness 0.15)) (justify left bottom) hide)
    )
    (property "Author" "Antmicro" (at 169.545 116.205 0)
      (effects (font (size 1.27 1.27) (thickness 0.15)) (justify left bottom) hide)
    )
    (property "Voltage" "" (at 167.005 116.205 0)
      (effects (font (size 1.27 1.27)) (justify left bottom) hide)
    )
    (property "Dielectric" "" (at 164.465 116.205 0)
      (effects (font (size 1.27 1.27)) (justify left bottom) hide)
    )
    (pin "1")
    (pin "2")
    (instances
      (project "kria-k26-devboard"
        (path ""
          (reference "C180") (unit 1)
        )
      )
    )
  )

  (symbol (lib_id "kria-k26-devboard:C_47u_16V_1206") (at 206.375 95.885 270) (unit 1)
    (in_bom yes) (on_board yes) (dnp no)
    (property "Reference" "C181" (at 207.01 96.52 90)
      (effects (font (size 1.524 1.524)) (justify left))
    )
    (property "Value" "C_47u_16V_1206" (at 202.565 95.885 0)
      (effects (font (size 1.27 1.27) (thickness 0.15)) (justify left bottom) hide)
    )
    (property "Footprint" "kria-k26-devboard-footprints:C_1206_3216Metric" (at 211.455 100.965 0)
      (effects (font (size 1.27 1.27) (thickness 0.15)) (justify left bottom) hide)
    )
    (property "Datasheet" " " (at 206.375 95.885 0)
      (effects (font (size 1.27 1.27) (thickness 0.15)) (justify left bottom) hide)
    )
    (property "Manufacturer" "TDK" (at 216.535 100.965 0)
      (effects (font (size 1.27 1.27) (thickness 0.15)) (justify left bottom) hide)
    )
    (property "MPN" "C3216X5R1C476M160AB" (at 213.995 100.965 0)
      (effects (font (size 1.27 1.27) (thickness 0.15)) (justify left bottom) hide)
    )
    (property "Val" "47u/16V" (at 207.01 100.33 90)
      (effects (font (size 1.27 1.27) (thickness 0.15)) (justify left))
    )
    (property "License" "Apache-2.0" (at 183.515 116.205 0)
      (effects (font (size 1.27 1.27) (thickness 0.15)) (justify left bottom) hide)
    )
    (property "Author" "Antmicro" (at 180.975 116.205 0)
      (effects (font (size 1.27 1.27) (thickness 0.15)) (justify left bottom) hide)
    )
    (property "Voltage" "" (at 178.435 116.205 0)
      (effects (font (size 1.27 1.27)) (justify left bottom) hide)
    )
    (property "Dielectric" "" (at 175.895 116.205 0)
      (effects (font (size 1.27 1.27)) (justify left bottom) hide)
    )
    (pin "1")
    (pin "2")
    (instances
      (project "kria-k26-devboard"
        (path ""
          (reference "C181") (unit 1)
        )
      )
    )
  )

  (symbol (lib_id "kria-k26-devboard:C_100n_0402") (at 217.805 95.885 270) (unit 1)
    (in_bom yes) (on_board yes) (dnp no)
    (property "Reference" "C182" (at 219.71 97.155 90)
      (effects (font (size 1.524 1.524)) (justify left))
    )
    (property "Value" "C_100n_0402" (at 207.645 116.205 0)
      (effects (font (size 1.27 1.27) (thickness 0.15)) (justify left bottom) hide)
    )
    (property "Footprint" "kria-k26-devboard-footprints:C_0402_1005Metric" (at 205.105 116.205 0)
      (effects (font (size 1.27 1.27) (thickness 0.15)) (justify left bottom) hide)
    )
    (property "Datasheet" "https://www.murata.com/products/productdetail?partno=GRM155R61H104KE14%23" (at 202.565 116.205 0)
      (effects (font (size 1.27 1.27) (thickness 0.15)) (justify left bottom) hide)
    )
    (property "Manufacturer" "Murata" (at 197.485 116.205 0)
      (effects (font (size 1.27 1.27) (thickness 0.15)) (justify left bottom) hide)
    )
    (property "MPN" "GRM155R61H104KE14D" (at 200.025 116.205 0)
      (effects (font (size 1.27 1.27) (thickness 0.15)) (justify left bottom) hide)
    )
    (property "Val" "100n" (at 219.71 99.695 90)
      (effects (font (size 1.27 1.27) (thickness 0.15)) (justify left))
    )
    (property "License" "Apache-2.0" (at 194.945 116.205 0)
      (effects (font (size 1.27 1.27) (thickness 0.15)) (justify left bottom) hide)
    )
    (property "Author" "Antmicro" (at 192.405 116.205 0)
      (effects (font (size 1.27 1.27) (thickness 0.15)) (justify left bottom) hide)
    )
    (property "Voltage" "50V" (at 189.865 116.205 0)
      (effects (font (size 1.27 1.27)) (justify left bottom) hide)
    )
    (property "Dielectric" "X5R" (at 187.325 116.205 0)
      (effects (font (size 1.27 1.27)) (justify left bottom) hide)
    )
    (pin "1")
    (pin "2")
    (instances
      (project "kria-k26-devboard"
        (path ""
          (reference "C182") (unit 1)
        )
      )
    )
  )

  (symbol (lib_id "kria-k26-devboard:GND") (at 217.805 107.315 0) (unit 1)
    (in_bom yes) (on_board yes) (dnp no)
    (property "Reference" "#PWR0364" (at 217.805 113.665 0)
      (effects (font (size 1.27 1.27)) hide)
    )
    (property "Value" "GND" (at 217.932 111.7092 0)
      (effects (font (size 1.27 1.27)))
    )
    (property "Footprint" "" (at 226.695 114.935 0)
      (effects (font (size 1.27 1.27) (thickness 0.15)) (justify left bottom) hide)
    )
    (property "Datasheet" "" (at 226.695 120.015 0)
      (effects (font (size 1.27 1.27) (thickness 0.15)) (justify left bottom) hide)
    )
    (property "Author" "Antmicro" (at 226.695 114.935 0)
      (effects (font (size 1.27 1.27) (thickness 0.15)) (justify left bottom) hide)
    )
    (property "License" "Apache-2.0" (at 226.695 117.475 0)
      (effects (font (size 1.27 1.27) (thickness 0.15)) (justify left bottom) hide)
    )
    (pin "1")
    (instances
      (project "kria-k26-devboard"
        (path ""
          (reference "#PWR0364") (unit 1)
        )
      )
    )
  )

  (symbol (lib_id "kria-k26-devboard:C_22u_100V_2220") (at 86.995 97.79 270) (unit 1)
    (in_bom no) (on_board yes) (dnp yes)
    (property "Reference" "C176" (at 87.63 98.425 90)
      (effects (font (size 1.524 1.524)) (justify left))
    )
    (property "Value" "C_22u_100V_2220" (at 83.185 97.79 0)
      (effects (font (size 1.27 1.27) (thickness 0.15)) (justify left bottom) hide)
    )
    (property "Footprint" "kria-k26-devboard-footprints:C_2220_5650Metric" (at 92.075 102.87 0)
      (effects (font (size 1.27 1.27) (thickness 0.15)) (justify left bottom) hide)
    )
    (property "Datasheet" " " (at 86.995 97.79 0)
      (effects (font (size 1.27 1.27) (thickness 0.15)) (justify left bottom) hide)
    )
    (property "Manufacturer" "TDK" (at 97.155 102.87 0)
      (effects (font (size 1.27 1.27) (thickness 0.15)) (justify left bottom) hide)
    )
    (property "MPN" "C5750X7S2A226M280KB" (at 94.615 102.87 0)
      (effects (font (size 1.27 1.27) (thickness 0.15)) (justify left bottom) hide)
    )
    (property "Val" "22u/100V" (at 88.265 89.535 0)
      (effects (font (size 1.27 1.27) (thickness 0.15)) (justify left) hide)
    )
    (property "License" "Apache-2.0" (at 64.135 118.11 0)
      (effects (font (size 1.27 1.27) (thickness 0.15)) (justify left bottom) hide)
    )
    (property "Author" "Antmicro" (at 61.595 118.11 0)
      (effects (font (size 1.27 1.27) (thickness 0.15)) (justify left bottom) hide)
    )
    (property "Voltage" "" (at 59.055 118.11 0)
      (effects (font (size 1.27 1.27)) (justify left bottom) hide)
    )
    (property "Dielectric" "" (at 56.515 118.11 0)
      (effects (font (size 1.27 1.27)) (justify left bottom) hide)
    )
    (property "DNP" "DNP" (at 90.17 102.235 90)
      (effects (font (size 1.27 1.27)))
    )
    (pin "1")
    (pin "2")
    (instances
      (project "kria-k26-devboard"
        (path ""
          (reference "C176") (unit 1)
        )
      )
    )
  )

  (symbol (lib_id "kria-k26-devboard:C_22u_100V_2220") (at 93.98 97.79 270) (unit 1)
    (in_bom no) (on_board yes) (dnp yes)
    (property "Reference" "C177" (at 94.615 98.425 90)
      (effects (font (size 1.524 1.524)) (justify left))
    )
    (property "Value" "C_22u_100V_2220" (at 90.17 97.79 0)
      (effects (font (size 1.27 1.27) (thickness 0.15)) (justify left bottom) hide)
    )
    (property "Footprint" "kria-k26-devboard-footprints:C_2220_5650Metric" (at 99.06 102.87 0)
      (effects (font (size 1.27 1.27) (thickness 0.15)) (justify left bottom) hide)
    )
    (property "Datasheet" " " (at 93.98 97.79 0)
      (effects (font (size 1.27 1.27) (thickness 0.15)) (justify left bottom) hide)
    )
    (property "Manufacturer" "TDK" (at 104.14 102.87 0)
      (effects (font (size 1.27 1.27) (thickness 0.15)) (justify left bottom) hide)
    )
    (property "MPN" "C5750X7S2A226M280KB" (at 101.6 102.87 0)
      (effects (font (size 1.27 1.27) (thickness 0.15)) (justify left bottom) hide)
    )
    (property "Val" "22u/100V" (at 95.25 89.535 0)
      (effects (font (size 1.27 1.27) (thickness 0.15)) (justify left) hide)
    )
    (property "License" "Apache-2.0" (at 71.12 118.11 0)
      (effects (font (size 1.27 1.27) (thickness 0.15)) (justify left bottom) hide)
    )
    (property "Author" "Antmicro" (at 68.58 118.11 0)
      (effects (font (size 1.27 1.27) (thickness 0.15)) (justify left bottom) hide)
    )
    (property "Voltage" "" (at 66.04 118.11 0)
      (effects (font (size 1.27 1.27)) (justify left bottom) hide)
    )
    (property "Dielectric" "" (at 63.5 118.11 0)
      (effects (font (size 1.27 1.27)) (justify left bottom) hide)
    )
    (property "DNP" "DNP" (at 97.155 102.235 90)
      (effects (font (size 1.27 1.27)))
    )
    (pin "1")
    (pin "2")
    (instances
      (project "kria-k26-devboard"
        (path ""
          (reference "C177") (unit 1)
        )
      )
    )
  )

  (symbol (lib_id "kria-k26-devboard:C_22u_100V_2220") (at 100.965 97.79 270) (unit 1)
    (in_bom no) (on_board yes) (dnp yes)
    (property "Reference" "C178" (at 101.6 98.425 90)
      (effects (font (size 1.524 1.524)) (justify left))
    )
    (property "Value" "C_22u_100V_2220" (at 97.155 97.79 0)
      (effects (font (size 1.27 1.27) (thickness 0.15)) (justify left bottom) hide)
    )
    (property "Footprint" "kria-k26-devboard-footprints:C_2220_5650Metric" (at 106.045 102.87 0)
      (effects (font (size 1.27 1.27) (thickness 0.15)) (justify left bottom) hide)
    )
    (property "Datasheet" " " (at 100.965 97.79 0)
      (effects (font (size 1.27 1.27) (thickness 0.15)) (justify left bottom) hide)
    )
    (property "Manufacturer" "TDK" (at 111.125 102.87 0)
      (effects (font (size 1.27 1.27) (thickness 0.15)) (justify left bottom) hide)
    )
    (property "MPN" "C5750X7S2A226M280KB" (at 108.585 102.87 0)
      (effects (font (size 1.27 1.27) (thickness 0.15)) (justify left bottom) hide)
    )
    (property "Val" "22u/100V" (at 102.235 89.535 0)
      (effects (font (size 1.27 1.27) (thickness 0.15)) (justify left) hide)
    )
    (property "License" "Apache-2.0" (at 78.105 118.11 0)
      (effects (font (size 1.27 1.27) (thickness 0.15)) (justify left bottom) hide)
    )
    (property "Author" "Antmicro" (at 75.565 118.11 0)
      (effects (font (size 1.27 1.27) (thickness 0.15)) (justify left bottom) hide)
    )
    (property "Voltage" "" (at 73.025 118.11 0)
      (effects (font (size 1.27 1.27)) (justify left bottom) hide)
    )
    (property "Dielectric" "" (at 70.485 118.11 0)
      (effects (font (size 1.27 1.27)) (justify left bottom) hide)
    )
    (property "DNP" "DNP" (at 104.14 102.235 90)
      (effects (font (size 1.27 1.27)))
    )
    (pin "1")
    (pin "2")
    (instances
      (project "kria-k26-devboard"
        (path ""
          (reference "C178") (unit 1)
        )
      )
    )
  )

  (symbol (lib_id "kria-k26-devboard:C_22u_100V_2220") (at 107.95 97.79 270) (unit 1)
    (in_bom no) (on_board yes) (dnp yes)
    (property "Reference" "C179" (at 108.585 98.425 90)
      (effects (font (size 1.524 1.524)) (justify left))
    )
    (property "Value" "C_22u_100V_2220" (at 104.14 97.79 0)
      (effects (font (size 1.27 1.27) (thickness 0.15)) (justify left bottom) hide)
    )
    (property "Footprint" "kria-k26-devboard-footprints:C_2220_5650Metric" (at 113.03 102.87 0)
      (effects (font (size 1.27 1.27) (thickness 0.15)) (justify left bottom) hide)
    )
    (property "Datasheet" " " (at 107.95 97.79 0)
      (effects (font (size 1.27 1.27) (thickness 0.15)) (justify left bottom) hide)
    )
    (property "Manufacturer" "TDK" (at 118.11 102.87 0)
      (effects (font (size 1.27 1.27) (thickness 0.15)) (justify left bottom) hide)
    )
    (property "MPN" "C5750X7S2A226M280KB" (at 115.57 102.87 0)
      (effects (font (size 1.27 1.27) (thickness 0.15)) (justify left bottom) hide)
    )
    (property "Val" "22u/100V" (at 109.22 89.535 0)
      (effects (font (size 1.27 1.27) (thickness 0.15)) (justify left) hide)
    )
    (property "License" "Apache-2.0" (at 85.09 118.11 0)
      (effects (font (size 1.27 1.27) (thickness 0.15)) (justify left bottom) hide)
    )
    (property "Author" "Antmicro" (at 82.55 118.11 0)
      (effects (font (size 1.27 1.27) (thickness 0.15)) (justify left bottom) hide)
    )
    (property "Voltage" "" (at 80.01 118.11 0)
      (effects (font (size 1.27 1.27)) (justify left bottom) hide)
    )
    (property "Dielectric" "" (at 77.47 118.11 0)
      (effects (font (size 1.27 1.27)) (justify left bottom) hide)
    )
    (property "DNP" "DNP" (at 111.125 102.235 90)
      (effects (font (size 1.27 1.27)))
    )
    (pin "1")
    (pin "2")
    (instances
      (project "kria-k26-devboard"
        (path ""
          (reference "C179") (unit 1)
        )
      )
    )
  )

  (symbol (lib_id "kria-k26-devboard:R_15k_2010") (at 150.495 92.075 270) (unit 1)
    (in_bom yes) (on_board yes) (dnp no) (fields_autoplaced)
    (property "Reference" "R154" (at 153.035 93.345 90)
      (effects (font (size 1.524 1.524)) (justify left))
    )
    (property "Value" "R_15k_2010" (at 146.685 92.075 0)
      (effects (font (size 1.27 1.27) (thickness 0.15)) (justify left bottom) hide)
    )
    (property "Footprint" "kria-k26-devboard-footprints:R_2010_5025Metric" (at 155.575 97.155 0)
      (effects (font (size 1.27 1.27) (thickness 0.15)) (justify left bottom) hide)
    )
    (property "Datasheet" "https://www.bourns.com/docs/product-datasheets/cr.pdf" (at 150.495 92.075 0)
      (effects (font (size 1.27 1.27) (thickness 0.15)) (justify left bottom) hide)
    )
    (property "Manufacturer" "Bourns" (at 160.655 97.155 0)
      (effects (font (size 1.27 1.27) (thickness 0.15)) (justify left bottom) hide)
    )
    (property "MPN" "CR2010-FX-1502ELF" (at 158.115 97.155 0)
      (effects (font (size 1.27 1.27) (thickness 0.15)) (justify left bottom) hide)
    )
    (property "Val" "15k" (at 153.035 96.5199 90)
      (effects (font (size 1.27 1.27) (thickness 0.15)) (justify left))
    )
    (property "License" "Apache-2.0" (at 125.095 112.395 0)
      (effects (font (size 1.27 1.27) (thickness 0.15)) (justify left bottom) hide)
    )
    (property "Author" "Antmicro" (at 122.555 112.395 0)
      (effects (font (size 1.27 1.27) (thickness 0.15)) (justify left bottom) hide)
    )
    (property "Tolerance" "1%" (at 140.335 112.395 0)
      (effects (font (size 1.27 1.27)) (justify left bottom) hide)
    )
    (pin "1")
    (pin "2")
    (instances
      (project "kria-k26-devboard"
        (path ""
          (reference "R154") (unit 1)
        )
      )
    )
  )

  (symbol (lib_id "kria-k26-devboard:LED_G_0603_LG_L29K-G2J1-24-Z") (at 145.415 97.79 270) (unit 1)
    (in_bom yes) (on_board yes) (dnp no) (fields_autoplaced)
    (property "Reference" "D11" (at 142.24 100.33 90)
      (effects (font (size 1.524 1.524)) (justify right))
    )
    (property "Value" "LED_G_0603_LG_L29K-G2J1-24-Z" (at 142.875 82.55 0)
      (effects (font (size 1.27 1.27) (thickness 0.15)) (justify left bottom) hide)
    )
    (property "Footprint" "kria-k26-devboard-footprints:LED_0603_1608Metric_G" (at 150.495 102.87 0)
      (effects (font (size 1.27 1.27) (thickness 0.15)) (justify left bottom) hide)
    )
    (property "Datasheet" "https://dammedia.osram.info/media/resource/hires/osram-dam-2493945/LG%20L29K.pdf" (at 153.035 102.87 0)
      (effects (font (size 1.27 1.27) (thickness 0.15)) (justify left bottom) hide)
    )
    (property "MPN" "LG L29K-G2J1-24-Z" (at 143.51 103.505 0)
      (effects (font (size 1.27 1.27) (thickness 0.15)) (justify left bottom) hide)
    )
    (property "Manufacturer" "OSRAM" (at 173.355 102.87 0)
      (effects (font (size 1.27 1.27) (thickness 0.15)) (justify left bottom) hide)
    )
    (property "Author" "Antmicro" (at 125.095 120.65 0)
      (effects (font (size 1.27 1.27) (thickness 0.15)) (justify left bottom) hide)
    )
    (property "License" "Apache-2.0" (at 122.555 120.65 0)
      (effects (font (size 1.27 1.27) (thickness 0.15)) (justify left bottom) hide)
    )
    (property "Color" "Green" (at 142.24 102.87 90)
      (effects (font (size 1.27 1.27)) (justify right))
    )
    (pin "1")
    (pin "2")
    (instances
      (project "kria-k26-devboard"
        (path ""
          (reference "D11") (unit 1)
        )
      )
    )
  )

  (symbol (lib_id "kria-k26-devboard:TP_0.75mm_SMD") (at 196.85 89.535 90) (unit 1)
    (in_bom yes) (on_board yes) (dnp no) (fields_autoplaced)
    (property "Reference" "TP35" (at 198.755 86.3599 90)
      (effects (font (size 1.27 1.27)) (justify right))
    )
    (property "Value" "TP_0.75mm_SMD" (at 199.39 89.535 0)
      (effects (font (size 1.27 1.27) (thickness 0.15)) (justify left bottom) hide)
    )
    (property "Footprint" "kria-k26-devboard-footprints:TP_SMD_0.75mm" (at 191.77 84.455 0)
      (effects (font (size 1.27 1.27) (thickness 0.15)) (justify left bottom) hide)
    )
    (property "Datasheet" "" (at 189.23 84.455 0)
      (effects (font (size 1.27 1.27) (thickness 0.15)) (justify left bottom) hide)
    )
    (property "MPN" "" (at 196.85 89.535 0)
      (effects (font (size 1.27 1.27) (thickness 0.15)) (justify left bottom) hide)
    )
    (property "Manufacturer" "" (at 196.85 89.535 0)
      (effects (font (size 1.27 1.27) (thickness 0.15)) (justify left bottom) hide)
    )
    (property "Author" "Antmicro" (at 212.09 74.295 0)
      (effects (font (size 1.27 1.27) (thickness 0.15)) (justify left bottom) hide)
    )
    (property "License" "Apache-2.0" (at 214.63 74.295 0)
      (effects (font (size 1.27 1.27) (thickness 0.15)) (justify left bottom) hide)
    )
    (pin "1")
    (instances
      (project "kria-k26-devboard"
        (path ""
          (reference "TP35") (unit 1)
        )
      )
    )
  )

  (symbol (lib_id "kria-k26-devboard:TP_0.75mm_SMD") (at 153.035 89.535 90) (unit 1)
    (in_bom yes) (on_board yes) (dnp no) (fields_autoplaced)
    (property "Reference" "TP34" (at 154.94 86.3599 90)
      (effects (font (size 1.27 1.27)) (justify right))
    )
    (property "Value" "TP_0.75mm_SMD" (at 155.575 89.535 0)
      (effects (font (size 1.27 1.27) (thickness 0.15)) (justify left bottom) hide)
    )
    (property "Footprint" "kria-k26-devboard-footprints:TP_SMD_0.75mm" (at 147.955 84.455 0)
      (effects (font (size 1.27 1.27) (thickness 0.15)) (justify left bottom) hide)
    )
    (property "Datasheet" "" (at 145.415 84.455 0)
      (effects (font (size 1.27 1.27) (thickness 0.15)) (justify left bottom) hide)
    )
    (property "MPN" "" (at 153.035 89.535 0)
      (effects (font (size 1.27 1.27) (thickness 0.15)) (justify left bottom) hide)
    )
    (property "Manufacturer" "" (at 153.035 89.535 0)
      (effects (font (size 1.27 1.27) (thickness 0.15)) (justify left bottom) hide)
    )
    (property "Author" "Antmicro" (at 168.275 74.295 0)
      (effects (font (size 1.27 1.27) (thickness 0.15)) (justify left bottom) hide)
    )
    (property "License" "Apache-2.0" (at 170.815 74.295 0)
      (effects (font (size 1.27 1.27) (thickness 0.15)) (justify left bottom) hide)
    )
    (pin "1")
    (instances
      (project "kria-k26-devboard"
        (path ""
          (reference "TP34") (unit 1)
        )
      )
    )
  )

  (symbol (lib_id "kria-k26-devboard:R_63R4_0603") (at 153.67 63.5 270) (unit 1)
    (in_bom yes) (on_board yes) (dnp no) (fields_autoplaced)
    (property "Reference" "R116" (at 155.575 64.77 90)
      (effects (font (size 1.524 1.524)) (justify left))
    )
    (property "Value" "R_63R4_0603" (at 149.86 63.5 0)
      (effects (font (size 1.27 1.27) (thickness 0.15)) (justify left bottom) hide)
    )
    (property "Footprint" "kria-k26-devboard-footprints:R_0603_1608Metric" (at 158.75 68.58 0)
      (effects (font (size 1.27 1.27) (thickness 0.15)) (justify left bottom) hide)
    )
    (property "Datasheet" "https://www.bourns.com/docs/product-datasheets/cr.pdf" (at 153.67 63.5 0)
      (effects (font (size 1.27 1.27) (thickness 0.15)) (justify left bottom) hide)
    )
    (property "Manufacturer" "Bourns" (at 163.83 68.58 0)
      (effects (font (size 1.27 1.27) (thickness 0.15)) (justify left bottom) hide)
    )
    (property "MPN" "CR0603-FX-63R4ELF" (at 161.29 68.58 0)
      (effects (font (size 1.27 1.27) (thickness 0.15)) (justify left bottom) hide)
    )
    (property "Val" "63R4" (at 155.575 67.9449 90)
      (effects (font (size 1.27 1.27) (thickness 0.15)) (justify left))
    )
    (property "License" "Apache-2.0" (at 128.27 83.82 0)
      (effects (font (size 1.27 1.27) (thickness 0.15)) (justify left bottom) hide)
    )
    (property "Author" "Antmicro" (at 125.73 83.82 0)
      (effects (font (size 1.27 1.27) (thickness 0.15)) (justify left bottom) hide)
    )
    (property "Tolerance" "1%" (at 143.51 83.82 0)
      (effects (font (size 1.27 1.27)) (justify left bottom) hide)
    )
    (pin "1")
    (pin "2")
    (instances
      (project "kria-k26-devboard"
        (path ""
          (reference "R116") (unit 1)
        )
      )
    )
  )

  (symbol (lib_id "kria-k26-devboard:C_22u_100V_2220") (at 59.055 97.79 270) (unit 1)
    (in_bom yes) (on_board yes) (dnp no)
    (property "Reference" "C172" (at 59.69 98.425 90)
      (effects (font (size 1.524 1.524)) (justify left))
    )
    (property "Value" "C_22u_100V_2220" (at 55.245 97.79 0)
      (effects (font (size 1.27 1.27) (thickness 0.15)) (justify left bottom) hide)
    )
    (property "Footprint" "kria-k26-devboard-footprints:C_2220_5650Metric" (at 64.135 102.87 0)
      (effects (font (size 1.27 1.27) (thickness 0.15)) (justify left bottom) hide)
    )
    (property "Datasheet" " " (at 59.055 97.79 0)
      (effects (font (size 1.27 1.27) (thickness 0.15)) (justify left bottom) hide)
    )
    (property "Manufacturer" "TDK" (at 69.215 102.87 0)
      (effects (font (size 1.27 1.27) (thickness 0.15)) (justify left bottom) hide)
    )
    (property "MPN" "C5750X7S2A226M280KB" (at 66.675 102.87 0)
      (effects (font (size 1.27 1.27) (thickness 0.15)) (justify left bottom) hide)
    )
    (property "Val" "22u/100V" (at 60.325 89.535 0)
      (effects (font (size 1.27 1.27) (thickness 0.15)) (justify left) hide)
    )
    (property "License" "Apache-2.0" (at 36.195 118.11 0)
      (effects (font (size 1.27 1.27) (thickness 0.15)) (justify left bottom) hide)
    )
    (property "Author" "Antmicro" (at 33.655 118.11 0)
      (effects (font (size 1.27 1.27) (thickness 0.15)) (justify left bottom) hide)
    )
    (property "Voltage" "" (at 31.115 118.11 0)
      (effects (font (size 1.27 1.27)) (justify left bottom) hide)
    )
    (property "Dielectric" "" (at 28.575 118.11 0)
      (effects (font (size 1.27 1.27)) (justify left bottom) hide)
    )
    (pin "1")
    (pin "2")
    (instances
      (project "kria-k26-devboard"
        (path ""
          (reference "C172") (unit 1)
        )
      )
    )
  )

  (symbol (lib_id "kria-k26-devboard:C_22u_100V_2220") (at 66.04 97.79 270) (unit 1)
    (in_bom yes) (on_board yes) (dnp no)
    (property "Reference" "C173" (at 66.675 98.425 90)
      (effects (font (size 1.524 1.524)) (justify left))
    )
    (property "Value" "C_22u_100V_2220" (at 62.23 97.79 0)
      (effects (font (size 1.27 1.27) (thickness 0.15)) (justify left bottom) hide)
    )
    (property "Footprint" "kria-k26-devboard-footprints:C_2220_5650Metric" (at 71.12 102.87 0)
      (effects (font (size 1.27 1.27) (thickness 0.15)) (justify left bottom) hide)
    )
    (property "Datasheet" " " (at 66.04 97.79 0)
      (effects (font (size 1.27 1.27) (thickness 0.15)) (justify left bottom) hide)
    )
    (property "Manufacturer" "TDK" (at 76.2 102.87 0)
      (effects (font (size 1.27 1.27) (thickness 0.15)) (justify left bottom) hide)
    )
    (property "MPN" "C5750X7S2A226M280KB" (at 73.66 102.87 0)
      (effects (font (size 1.27 1.27) (thickness 0.15)) (justify left bottom) hide)
    )
    (property "Val" "22u/100V" (at 67.31 89.535 0)
      (effects (font (size 1.27 1.27) (thickness 0.15)) (justify left) hide)
    )
    (property "License" "Apache-2.0" (at 43.18 118.11 0)
      (effects (font (size 1.27 1.27) (thickness 0.15)) (justify left bottom) hide)
    )
    (property "Author" "Antmicro" (at 40.64 118.11 0)
      (effects (font (size 1.27 1.27) (thickness 0.15)) (justify left bottom) hide)
    )
    (property "Voltage" "" (at 38.1 118.11 0)
      (effects (font (size 1.27 1.27)) (justify left bottom) hide)
    )
    (property "Dielectric" "" (at 35.56 118.11 0)
      (effects (font (size 1.27 1.27)) (justify left bottom) hide)
    )
    (pin "1")
    (pin "2")
    (instances
      (project "kria-k26-devboard"
        (path ""
          (reference "C173") (unit 1)
        )
      )
    )
  )

  (symbol (lib_id "kria-k26-devboard:C_22u_100V_2220") (at 73.025 97.79 270) (unit 1)
    (in_bom yes) (on_board yes) (dnp no)
    (property "Reference" "C174" (at 73.66 98.425 90)
      (effects (font (size 1.524 1.524)) (justify left))
    )
    (property "Value" "C_22u_100V_2220" (at 69.215 97.79 0)
      (effects (font (size 1.27 1.27) (thickness 0.15)) (justify left bottom) hide)
    )
    (property "Footprint" "kria-k26-devboard-footprints:C_2220_5650Metric" (at 78.105 102.87 0)
      (effects (font (size 1.27 1.27) (thickness 0.15)) (justify left bottom) hide)
    )
    (property "Datasheet" " " (at 73.025 97.79 0)
      (effects (font (size 1.27 1.27) (thickness 0.15)) (justify left bottom) hide)
    )
    (property "Manufacturer" "TDK" (at 83.185 102.87 0)
      (effects (font (size 1.27 1.27) (thickness 0.15)) (justify left bottom) hide)
    )
    (property "MPN" "C5750X7S2A226M280KB" (at 80.645 102.87 0)
      (effects (font (size 1.27 1.27) (thickness 0.15)) (justify left bottom) hide)
    )
    (property "Val" "22u/100V" (at 74.295 89.535 0)
      (effects (font (size 1.27 1.27) (thickness 0.15)) (justify left) hide)
    )
    (property "License" "Apache-2.0" (at 50.165 118.11 0)
      (effects (font (size 1.27 1.27) (thickness 0.15)) (justify left bottom) hide)
    )
    (property "Author" "Antmicro" (at 47.625 118.11 0)
      (effects (font (size 1.27 1.27) (thickness 0.15)) (justify left bottom) hide)
    )
    (property "Voltage" "" (at 45.085 118.11 0)
      (effects (font (size 1.27 1.27)) (justify left bottom) hide)
    )
    (property "Dielectric" "" (at 42.545 118.11 0)
      (effects (font (size 1.27 1.27)) (justify left bottom) hide)
    )
    (pin "1")
    (pin "2")
    (instances
      (project "kria-k26-devboard"
        (path ""
          (reference "C174") (unit 1)
        )
      )
    )
  )

  (symbol (lib_id "kria-k26-devboard:C_22u_100V_2220") (at 80.01 97.79 270) (unit 1)
    (in_bom yes) (on_board yes) (dnp no)
    (property "Reference" "C175" (at 80.645 98.425 90)
      (effects (font (size 1.524 1.524)) (justify left))
    )
    (property "Value" "C_22u_100V_2220" (at 76.2 97.79 0)
      (effects (font (size 1.27 1.27) (thickness 0.15)) (justify left bottom) hide)
    )
    (property "Footprint" "kria-k26-devboard-footprints:C_2220_5650Metric" (at 85.09 102.87 0)
      (effects (font (size 1.27 1.27) (thickness 0.15)) (justify left bottom) hide)
    )
    (property "Datasheet" " " (at 80.01 97.79 0)
      (effects (font (size 1.27 1.27) (thickness 0.15)) (justify left bottom) hide)
    )
    (property "Manufacturer" "TDK" (at 90.17 102.87 0)
      (effects (font (size 1.27 1.27) (thickness 0.15)) (justify left bottom) hide)
    )
    (property "MPN" "C5750X7S2A226M280KB" (at 87.63 102.87 0)
      (effects (font (size 1.27 1.27) (thickness 0.15)) (justify left bottom) hide)
    )
    (property "Val" "22u/100V" (at 81.28 89.535 0)
      (effects (font (size 1.27 1.27) (thickness 0.15)) (justify left) hide)
    )
    (property "License" "Apache-2.0" (at 57.15 118.11 0)
      (effects (font (size 1.27 1.27) (thickness 0.15)) (justify left bottom) hide)
    )
    (property "Author" "Antmicro" (at 54.61 118.11 0)
      (effects (font (size 1.27 1.27) (thickness 0.15)) (justify left bottom) hide)
    )
    (property "Voltage" "" (at 52.07 118.11 0)
      (effects (font (size 1.27 1.27)) (justify left bottom) hide)
    )
    (property "Dielectric" "" (at 49.53 118.11 0)
      (effects (font (size 1.27 1.27)) (justify left bottom) hide)
    )
    (pin "1")
    (pin "2")
    (instances
      (project "kria-k26-devboard"
        (path ""
          (reference "C175") (unit 1)
        )
      )
    )
  )

  (symbol (lib_id "kria-k26-devboard:GNDD") (at 100.965 102.87 0) (unit 1)
    (in_bom yes) (on_board yes) (dnp no)
    (property "Reference" "#PWR0113" (at 100.965 109.22 0)
      (effects (font (size 1.27 1.27)) hide)
    )
    (property "Value" "GNDD" (at 101.0666 106.807 0)
      (effects (font (size 1.27 1.27)))
    )
    (property "Footprint" "" (at 116.205 113.03 0)
      (effects (font (size 1.27 1.27) (thickness 0.15)) (justify left bottom) hide)
    )
    (property "Datasheet" "" (at 116.205 115.57 0)
      (effects (font (size 1.27 1.27) (thickness 0.15)) (justify left bottom) hide)
    )
    (property "Author" "Antmicro" (at 116.205 110.49 0)
      (effects (font (size 1.27 1.27) (thickness 0.15)) (justify left bottom) hide)
    )
    (property "License" "Apache-2.0" (at 116.205 113.03 0)
      (effects (font (size 1.27 1.27) (thickness 0.15)) (justify left bottom) hide)
    )
    (pin "1")
    (instances
      (project "kria-k26-devboard"
        (path ""
          (reference "#PWR0113") (unit 1)
        )
      )
    )
  )

  (symbol (lib_id "kria-k26-devboard:GNDD") (at 107.95 102.87 0) (unit 1)
    (in_bom yes) (on_board yes) (dnp no)
    (property "Reference" "#PWR0117" (at 107.95 109.22 0)
      (effects (font (size 1.27 1.27)) hide)
    )
    (property "Value" "GNDD" (at 108.0516 106.807 0)
      (effects (font (size 1.27 1.27)))
    )
    (property "Footprint" "" (at 123.19 113.03 0)
      (effects (font (size 1.27 1.27) (thickness 0.15)) (justify left bottom) hide)
    )
    (property "Datasheet" "" (at 123.19 115.57 0)
      (effects (font (size 1.27 1.27) (thickness 0.15)) (justify left bottom) hide)
    )
    (property "Author" "Antmicro" (at 123.19 110.49 0)
      (effects (font (size 1.27 1.27) (thickness 0.15)) (justify left bottom) hide)
    )
    (property "License" "Apache-2.0" (at 123.19 113.03 0)
      (effects (font (size 1.27 1.27) (thickness 0.15)) (justify left bottom) hide)
    )
    (pin "1")
    (instances
      (project "kria-k26-devboard"
        (path ""
          (reference "#PWR0117") (unit 1)
        )
      )
    )
  )

  (symbol (lib_id "kria-k26-devboard:GNDD") (at 93.98 102.87 0) (unit 1)
    (in_bom yes) (on_board yes) (dnp no)
    (property "Reference" "#PWR0112" (at 93.98 109.22 0)
      (effects (font (size 1.27 1.27)) hide)
    )
    (property "Value" "GNDD" (at 94.0816 106.807 0)
      (effects (font (size 1.27 1.27)))
    )
    (property "Footprint" "" (at 109.22 113.03 0)
      (effects (font (size 1.27 1.27) (thickness 0.15)) (justify left bottom) hide)
    )
    (property "Datasheet" "" (at 109.22 115.57 0)
      (effects (font (size 1.27 1.27) (thickness 0.15)) (justify left bottom) hide)
    )
    (property "Author" "Antmicro" (at 109.22 110.49 0)
      (effects (font (size 1.27 1.27) (thickness 0.15)) (justify left bottom) hide)
    )
    (property "License" "Apache-2.0" (at 109.22 113.03 0)
      (effects (font (size 1.27 1.27) (thickness 0.15)) (justify left bottom) hide)
    )
    (pin "1")
    (instances
      (project "kria-k26-devboard"
        (path ""
          (reference "#PWR0112") (unit 1)
        )
      )
    )
  )

  (symbol (lib_id "kria-k26-devboard:R_32k4_0805") (at 145.415 97.155 90) (unit 1)
    (in_bom yes) (on_board yes) (dnp no)
    (property "Reference" "R117" (at 137.795 93.3451 90)
      (effects (font (size 1.524 1.524)) (justify right))
    )
    (property "Value" "R_32k4_0805" (at 149.225 97.155 0)
      (effects (font (size 1.27 1.27) (thickness 0.15)) (justify left bottom) hide)
    )
    (property "Footprint" "kria-k26-devboard-footprints:R_0805_2012Metric" (at 140.335 92.075 0)
      (effects (font (size 1.27 1.27) (thickness 0.15)) (justify left bottom) hide)
    )
    (property "Datasheet" "https://www.bourns.com/docs/product-datasheets/cr.pdf" (at 145.415 97.155 0)
      (effects (font (size 1.27 1.27) (thickness 0.15)) (justify left bottom) hide)
    )
    (property "Manufacturer" "Bourns" (at 135.255 92.075 0)
      (effects (font (size 1.27 1.27) (thickness 0.15)) (justify left bottom) hide)
    )
    (property "MPN" "CR0805-FX-3242ELF" (at 137.795 92.075 0)
      (effects (font (size 1.27 1.27) (thickness 0.15)) (justify left bottom) hide)
    )
    (property "Val" "32k4" (at 137.795 95.885 90)
      (effects (font (size 1.27 1.27) (thickness 0.15)) (justify right))
    )
    (property "License" "Apache-2.0" (at 170.815 76.835 0)
      (effects (font (size 1.27 1.27) (thickness 0.15)) (justify left bottom) hide)
    )
    (property "Author" "Antmicro" (at 173.355 76.835 0)
      (effects (font (size 1.27 1.27) (thickness 0.15)) (justify left bottom) hide)
    )
    (property "Tolerance" "1%" (at 155.575 76.835 0)
      (effects (font (size 1.27 1.27)) (justify left bottom) hide)
    )
    (pin "1")
    (pin "2")
    (instances
      (project "kria-k26-devboard"
        (path ""
          (reference "R117") (unit 1)
        )
      )
    )
  )

  (symbol (lib_id "kria-k26-devboard:GNDD") (at 66.04 102.87 0) (unit 1)
    (in_bom yes) (on_board yes) (dnp no)
    (property "Reference" "#PWR0127" (at 66.04 109.22 0)
      (effects (font (size 1.27 1.27)) hide)
    )
    (property "Value" "GNDD" (at 66.1416 106.807 0)
      (effects (font (size 1.27 1.27)))
    )
    (property "Footprint" "" (at 81.28 113.03 0)
      (effects (font (size 1.27 1.27) (thickness 0.15)) (justify left bottom) hide)
    )
    (property "Datasheet" "" (at 81.28 115.57 0)
      (effects (font (size 1.27 1.27) (thickness 0.15)) (justify left bottom) hide)
    )
    (property "Author" "Antmicro" (at 81.28 110.49 0)
      (effects (font (size 1.27 1.27) (thickness 0.15)) (justify left bottom) hide)
    )
    (property "License" "Apache-2.0" (at 81.28 113.03 0)
      (effects (font (size 1.27 1.27) (thickness 0.15)) (justify left bottom) hide)
    )
    (pin "1")
    (instances
      (project "kria-k26-devboard"
        (path ""
          (reference "#PWR0127") (unit 1)
        )
      )
    )
  )

  (symbol (lib_id "kria-k26-devboard:GNDD") (at 80.01 102.87 0) (unit 1)
    (in_bom yes) (on_board yes) (dnp no)
    (property "Reference" "#PWR0110" (at 80.01 109.22 0)
      (effects (font (size 1.27 1.27)) hide)
    )
    (property "Value" "GNDD" (at 80.1116 106.807 0)
      (effects (font (size 1.27 1.27)))
    )
    (property "Footprint" "" (at 95.25 113.03 0)
      (effects (font (size 1.27 1.27) (thickness 0.15)) (justify left bottom) hide)
    )
    (property "Datasheet" "" (at 95.25 115.57 0)
      (effects (font (size 1.27 1.27) (thickness 0.15)) (justify left bottom) hide)
    )
    (property "Author" "Antmicro" (at 95.25 110.49 0)
      (effects (font (size 1.27 1.27) (thickness 0.15)) (justify left bottom) hide)
    )
    (property "License" "Apache-2.0" (at 95.25 113.03 0)
      (effects (font (size 1.27 1.27) (thickness 0.15)) (justify left bottom) hide)
    )
    (pin "1")
    (instances
      (project "kria-k26-devboard"
        (path ""
          (reference "#PWR0110") (unit 1)
        )
      )
    )
  )

  (symbol (lib_id "kria-k26-devboard:GNDD") (at 73.025 102.87 0) (unit 1)
    (in_bom yes) (on_board yes) (dnp no)
    (property "Reference" "#PWR0128" (at 73.025 109.22 0)
      (effects (font (size 1.27 1.27)) hide)
    )
    (property "Value" "GNDD" (at 73.1266 106.807 0)
      (effects (font (size 1.27 1.27)))
    )
    (property "Footprint" "" (at 88.265 113.03 0)
      (effects (font (size 1.27 1.27) (thickness 0.15)) (justify left bottom) hide)
    )
    (property "Datasheet" "" (at 88.265 115.57 0)
      (effects (font (size 1.27 1.27) (thickness 0.15)) (justify left bottom) hide)
    )
    (property "Author" "Antmicro" (at 88.265 110.49 0)
      (effects (font (size 1.27 1.27) (thickness 0.15)) (justify left bottom) hide)
    )
    (property "License" "Apache-2.0" (at 88.265 113.03 0)
      (effects (font (size 1.27 1.27) (thickness 0.15)) (justify left bottom) hide)
    )
    (pin "1")
    (instances
      (project "kria-k26-devboard"
        (path ""
          (reference "#PWR0128") (unit 1)
        )
      )
    )
  )

  (symbol (lib_id "kria-k26-devboard:GNDD") (at 59.055 102.87 0) (unit 1)
    (in_bom yes) (on_board yes) (dnp no)
    (property "Reference" "#PWR0126" (at 59.055 109.22 0)
      (effects (font (size 1.27 1.27)) hide)
    )
    (property "Value" "GNDD" (at 59.1566 106.807 0)
      (effects (font (size 1.27 1.27)))
    )
    (property "Footprint" "" (at 74.295 113.03 0)
      (effects (font (size 1.27 1.27) (thickness 0.15)) (justify left bottom) hide)
    )
    (property "Datasheet" "" (at 74.295 115.57 0)
      (effects (font (size 1.27 1.27) (thickness 0.15)) (justify left bottom) hide)
    )
    (property "Author" "Antmicro" (at 74.295 110.49 0)
      (effects (font (size 1.27 1.27) (thickness 0.15)) (justify left bottom) hide)
    )
    (property "License" "Apache-2.0" (at 74.295 113.03 0)
      (effects (font (size 1.27 1.27) (thickness 0.15)) (justify left bottom) hide)
    )
    (pin "1")
    (instances
      (project "kria-k26-devboard"
        (path ""
          (reference "#PWR0126") (unit 1)
        )
      )
    )
  )

  (symbol (lib_id "kria-k26-devboard:GNDD") (at 145.415 107.95 0) (unit 1)
    (in_bom yes) (on_board yes) (dnp no)
    (property "Reference" "#PWR0109" (at 145.415 114.3 0)
      (effects (font (size 1.27 1.27)) hide)
    )
    (property "Value" "GNDD" (at 145.5166 111.887 0)
      (effects (font (size 1.27 1.27)))
    )
    (property "Footprint" "" (at 160.655 118.11 0)
      (effects (font (size 1.27 1.27) (thickness 0.15)) (justify left bottom) hide)
    )
    (property "Datasheet" "" (at 160.655 120.65 0)
      (effects (font (size 1.27 1.27) (thickness 0.15)) (justify left bottom) hide)
    )
    (property "Author" "Antmicro" (at 160.655 115.57 0)
      (effects (font (size 1.27 1.27) (thickness 0.15)) (justify left bottom) hide)
    )
    (property "License" "Apache-2.0" (at 160.655 118.11 0)
      (effects (font (size 1.27 1.27) (thickness 0.15)) (justify left bottom) hide)
    )
    (pin "1")
    (instances
      (project "kria-k26-devboard"
        (path ""
          (reference "#PWR0109") (unit 1)
        )
      )
    )
  )

  (symbol (lib_id "kria-k26-devboard:GNDD") (at 86.995 102.87 0) (unit 1)
    (in_bom yes) (on_board yes) (dnp no)
    (property "Reference" "#PWR0111" (at 86.995 109.22 0)
      (effects (font (size 1.27 1.27)) hide)
    )
    (property "Value" "GNDD" (at 87.0966 106.807 0)
      (effects (font (size 1.27 1.27)))
    )
    (property "Footprint" "" (at 102.235 113.03 0)
      (effects (font (size 1.27 1.27) (thickness 0.15)) (justify left bottom) hide)
    )
    (property "Datasheet" "" (at 102.235 115.57 0)
      (effects (font (size 1.27 1.27) (thickness 0.15)) (justify left bottom) hide)
    )
    (property "Author" "Antmicro" (at 102.235 110.49 0)
      (effects (font (size 1.27 1.27) (thickness 0.15)) (justify left bottom) hide)
    )
    (property "License" "Apache-2.0" (at 102.235 113.03 0)
      (effects (font (size 1.27 1.27) (thickness 0.15)) (justify left bottom) hide)
    )
    (pin "1")
    (instances
      (project "kria-k26-devboard"
        (path ""
          (reference "#PWR0111") (unit 1)
        )
      )
    )
  )
)
